# S9S_MB_2U (Grand Teton) — schematic netlist excerpt (pin names and nets, part order shuffled) for the footprints in the layout excerpt that follows; sources: Cadence DE-HDL packaged netlist, KiCad conversion of 03242023_DA0F0TMBIJ0_F0T_Motherboard_J_brd_V01_OCP.brd

C865  Q_CAP_DIFFBUS  DIFF BUS_0.22UF 6.3V 20% X6S  pkg C0201  page 174 : \1\ = P5E_CPU0_PE1_TX_C_DP<2> ; \2\ = P5E_CPU0_PE1_TX_DP<2>
R3495  Q_RES  100K 1% EMPTY  pkg 0402LF  page 150 : A = GPU_FPGA_EROT_RECOV_BUF_R_N ; B = GND
D88  Q_LED  IC  pkg SMLF  page 255 : A = LED_PWRGD_SYS_PWROK_R ; C = LED_PWRGD_SYS_PWROK_R_D

(kicad_pcb
	(version 20260206)
	(generator "pcbnew")
	(generator_version "10.0")
	(general
		(thickness 1.6)
		(legacy_teardrops no)
	)
	(paper "A4")
	(title_block
		(title "03242023_DA0F0TMBIJ0_F0T_Motherboard_J_brd_V01_OCP.brd")
		(comment 1 "Grand Teton / footprints 1513-1515 of 6105")
	)
	(layers
		(0 "F.Cu" signal "TOP")
		(4 "In1.Cu" signal "GND")
		(6 "In2.Cu" signal "IN1")
		(8 "In3.Cu" signal "GND1")
		(10 "In4.Cu" signal "IN2")
		(12 "In5.Cu" signal "GND2")
		(14 "In6.Cu" signal "IN3")
		(16 "In7.Cu" signal "GND3")
		(18 "In8.Cu" signal "VCC")
		(20 "In9.Cu" signal "VCC1")
		(22 "In10.Cu" signal "GND4")
		(24 "In11.Cu" signal "IN4")
		(26 "In12.Cu" signal "GND5")
		(28 "In13.Cu" signal "IN5")
		(30 "In14.Cu" signal "GND6")
		(32 "In15.Cu" signal "IN6")
		(34 "In16.Cu" signal "GND7")
		(2 "B.Cu" signal "BOTTOM")
		(9 "F.Adhes" user "F.Adhesive")
		(11 "B.Adhes" user "B.Adhesive")
		(13 "F.Paste" user "Package Geometry/Pastemask Top")
		(15 "B.Paste" user "Package Geometry/Pastemask Bottom")
		(5 "F.SilkS" user "Ref Des/Silkscreen Top")
		(7 "B.SilkS" user "Ref Des/Silkscreen Bottom")
		(1 "F.Mask" user "Board Geometry/Soldermask Top")
		(3 "B.Mask" user "Board Geometry/Soldermask Bottom")
		(17 "Dwgs.User" user "User.Drawings")
		(19 "Cmts.User" user "User.Comments")
		(21 "Eco1.User" user "User.Eco1")
		(23 "Eco2.User" user "User.Eco2")
		(25 "Edge.Cuts" user "Board Geometry/Outline")
		(27 "Margin" user)
		(31 "F.CrtYd" user "Package Geometry/Place Bound Top")
		(29 "B.CrtYd" user "Package Geometry/Place Bound Bottom")
		(35 "F.Fab" user "Ref Des/Assembly Top")
		(33 "B.Fab" user "Ref Des/Assembly Bottom")
	)
	(footprint ""
		(layer "F.Cu")
		(at 90.582496 -70.78599)
		(property "Reference" "D88"
			(at -46.009306 50.178462 90)
			(unlocked yes)
			(layer "F.SilkS")
			(effects
				(font
					(size 0.635 0.4064)
					(thickness 0.1524)
				)
				(justify left)
			)
		)
		(property "Value" ""
			(at 0 0 0)
			(layer "F.Fab")
			(effects
				(font
					(size 1.27 1.27)
				)
			)
		)
		(duplicate_pad_numbers_are_jumpers no)
		(fp_line
			(start -0.90678 0.4826)
			(end -0.90678 -0.4699)
			(stroke
				(width 0.1524)
				(type default)
			)
			(layer "F.SilkS")
		)
		(fp_line
			(start -0.89408 -0.4826)
			(end 0.90678 -0.4826)
			(stroke
				(width 0.1524)
				(type default)
			)
			(layer "F.SilkS")
		)
		(fp_line
			(start -0.79248 -0.4826)
			(end 1.03378 -0.4826)
			(stroke
				(width 0.1524)
				(type default)
			)
			(layer "F.SilkS")
		)
		(fp_line
			(start -0.64008 -0.4826)
			(end 1.16078 -0.4826)
			(stroke
				(width 0.1524)
				(type default)
			)
			(layer "F.SilkS")
		)
		(fp_line
			(start 0.90678 -0.4826)
			(end 0.90678 0.4826)
			(stroke
				(width 0.1524)
				(type default)
			)
			(layer "F.SilkS")
		)
		(fp_line
			(start 0.90678 0.4826)
			(end -0.90678 0.4826)
			(stroke
				(width 0.1524)
				(type default)
			)
			(layer "F.SilkS")
		)
		(fp_line
			(start 1.03378 -0.4826)
			(end 1.03378 0.4826)
			(stroke
				(width 0.1524)
				(type default)
			)
			(layer "F.SilkS")
		)
		(fp_line
			(start 1.03378 0.4826)
			(end -0.79248 0.4826)
			(stroke
				(width 0.1524)
				(type default)
			)
			(layer "F.SilkS")
		)
		(fp_line
			(start 1.16078 -0.4826)
			(end 1.16078 0.4826)
			(stroke
				(width 0.1524)
				(type default)
			)
			(layer "F.SilkS")
		)
		(fp_line
			(start 1.16078 0.4826)
			(end -0.64008 0.4826)
			(stroke
				(width 0.1524)
				(type default)
			)
			(layer "F.SilkS")
		)
		(fp_line
			(start -0.499872 -0.249936)
			(end 0.499872 -0.249936)
			(stroke
				(width 0.1)
				(type default)
			)
			(layer "F.Fab")
		)
		(fp_line
			(start -0.499872 0.249936)
			(end -0.499872 -0.249936)
			(stroke
				(width 0.1)
				(type default)
			)
			(layer "F.Fab")
		)
		(fp_line
			(start 0.499872 -0.249936)
			(end 0.499872 0.249936)
			(stroke
				(width 0.1)
				(type default)
			)
			(layer "F.Fab")
		)
		(fp_line
			(start 0.499872 0.249936)
			(end -0.499872 0.249936)
			(stroke
				(width 0.1)
				(type default)
			)
			(layer "F.Fab")
		)
		(pad "A" smd rect
			(at -0.47498 0)
			(size 0.6096 0.7112)
			(layers "F.Cu" "F.Mask" "F.Paste")
			(net "LED_PWRGD_SYS_PWROK_R")
		)
		(pad "C" smd rect
			(at 0.47498 0)
			(size 0.6096 0.7112)
			(layers "F.Cu" "F.Mask" "F.Paste")
			(net "LED_PWRGD_SYS_PWROK_R_D")
		)
	)
	(footprint ""
		(layer "F.Cu")
		(at 427.592236 -17.612614 90)
		(property "Reference" "C865"
			(at 0 0 90)
			(layer "F.SilkS")
			(hide yes)
			(effects
				(font
					(size 1.27 1.27)
				)
			)
		)
		(property "Value" ""
			(at 0 0 90)
			(layer "F.Fab")
			(effects
				(font
					(size 1.27 1.27)
				)
			)
		)
		(duplicate_pad_numbers_are_jumpers no)
		(fp_line
			(start 0.299974 -0.150114)
			(end 0.299974 0.150114)
			(stroke
				(width 0.1)
				(type default)
			)
			(layer "F.Fab")
		)
		(fp_line
			(start -0.299974 -0.150114)
			(end 0.299974 -0.150114)
			(stroke
				(width 0.1)
				(type default)
			)
			(layer "F.Fab")
		)
		(fp_line
			(start 0.299974 0.150114)
			(end -0.299974 0.150114)
			(stroke
				(width 0.1)
				(type default)
			)
			(layer "F.Fab")
		)
		(fp_line
			(start -0.299974 0.150114)
			(end -0.299974 -0.150114)
			(stroke
				(width 0.1)
				(type default)
			)
			(layer "F.Fab")
		)
		(pad "1" smd rect
			(at -0.2667 0 90)
			(size 0.3048 0.381)
			(layers "F.Cu" "F.Mask" "F.Paste")
			(net "P5E_CPU0_PE1_TX_C_DP<2>")
		)
		(pad "2" smd rect
			(at 0.2667 0 90)
			(size 0.3048 0.381)
			(layers "F.Cu" "F.Mask" "F.Paste")
			(net "P5E_CPU0_PE1_TX_DP<2>")
		)
	)
	(footprint ""
		(layer "F.Cu")
		(at 110.079282 -406.058116 90)
		(property "Reference" "R3495"
			(at 0 0 90)
			(layer "F.SilkS")
			(hide yes)
			(effects
				(font
					(size 1.27 1.27)
				)
			)
		)
		(property "Value" ""
			(at 0 0 90)
			(layer "F.Fab")
			(effects
				(font
					(size 1.27 1.27)
				)
			)
		)
		(duplicate_pad_numbers_are_jumpers no)
		(fp_line
			(start 0.7874 -0.4064)
			(end 0.7874 0.4064)
			(stroke
				(width 0.1524)
				(type default)
			)
			(layer "F.SilkS")
		)
		(fp_line
			(start -0.7874 -0.4064)
			(end 0.7874 -0.4064)
			(stroke
				(width 0.1524)
				(type default)
			)
			(layer "F.SilkS")
		)
		(fp_line
			(start 0.7874 0.4064)
			(end -0.7874 0.4064)
			(stroke
				(width 0.1524)
				(type default)
			)
			(layer "F.SilkS")
		)
		(fp_line
			(start -0.7874 0.4064)
			(end -0.7874 -0.4064)
			(stroke
				(width 0.1524)
				(type default)
			)
			(layer "F.SilkS")
		)
		(fp_line
			(start -0.12065 -0.305054)
			(end -0.12065 -0.2794)
			(stroke
				(width 0.1)
				(type default)
			)
			(layer "F.Fab")
		)
		(fp_line
			(start -0.67945 -0.305054)
			(end -0.12065 -0.305054)
			(stroke
				(width 0.1)
				(type default)
			)
			(layer "F.Fab")
		)
		(fp_line
			(start 0.67945 -0.3048)
			(end 0.67945 0.3048)
			(stroke
				(width 0.1)
				(type default)
			)
			(layer "F.Fab")
		)
		(fp_line
			(start 0.12065 -0.3048)
			(end 0.67945 -0.3048)
			(stroke
				(width 0.1)
				(type default)
			)
			(layer "F.Fab")
		)
		(fp_line
			(start 0.12065 -0.2794)
			(end 0.12065 -0.3048)
			(stroke
				(width 0.1)
				(type default)
			)
			(layer "F.Fab")
		)
		(fp_line
			(start -0.12065 -0.2794)
			(end 0.12065 -0.2794)
			(stroke
				(width 0.1)
				(type default)
			)
			(layer "F.Fab")
		)
		(fp_line
			(start 0.120396 0.2794)
			(end -0.12065 0.2794)
			(stroke
				(width 0.1)
				(type default)
			)
			(layer "F.Fab")
		)
		(fp_line
			(start -0.12065 0.2794)
			(end -0.12065 0.3048)
			(stroke
				(width 0.1)
				(type default)
			)
			(layer "F.Fab")
		)
		(fp_line
			(start 0.67945 0.3048)
			(end 0.120396 0.3048)
			(stroke
				(width 0.1)
				(type default)
			)
			(layer "F.Fab")
		)
		(fp_line
			(start 0.120396 0.3048)
			(end 0.120396 0.2794)
			(stroke
				(width 0.1)
				(type default)
			)
			(layer "F.Fab")
		)
		(fp_line
			(start -0.12065 0.3048)
			(end -0.67945 0.3048)
			(stroke
				(width 0.1)
				(type default)
			)
			(layer "F.Fab")
		)
		(fp_line
			(start -0.67945 0.3048)
			(end -0.67945 -0.305054)
			(stroke
				(width 0.1)
				(type default)
			)
			(layer "F.Fab")
		)
		(pad "1" smd circle
			(at -0.40005 0 90)
			(size 0 0)
			(layers "F.Cu" "F.Mask" "F.Paste")
			(net "GPU_FPGA_EROT_RECOV_BUF_R_N")
		)
		(pad "2" smd circle
			(at 0.40005 0 90)
			(size 0 0)
			(layers "F.Cu" "F.Mask" "F.Paste")
			(net "GND")
		)
	)
)
